# BASEBOARD_FAB2 (Tioga Pass) — schematic netlist excerpt (pin names and nets, part order shuffled) for the footprints in the layout excerpt that follows; sources: Cadence DE-HDL packaged netlist, KiCad conversion of Wiwynn_Tioga_Pass_MB.brd

C7A26  SC1U10V2KX-4-GP  10%  pkg SMD-BCG6  page 219 : \1\ = P5V_STBY ; \2\ = GND
R9E12  RES  200.0 1% CHIP  pkg 0402  page 187 : A = RST_PCIE_CPU_DEV3_R_N ; B = RST_PCIE_CPU_DEV3_N
R4U2  RES  2.21K 1% CHIP  pkg 0402  page 94 : A = PVPP_ABC ; B = FM_DIMM_EVENT_COD_N

(kicad_pcb
	(version 20260206)
	(generator "pcbnew")
	(generator_version "10.0")
	(general
		(thickness 1.6)
		(legacy_teardrops no)
	)
	(paper "A4")
	(title_block
		(title "Wiwynn_Tioga_Pass_MB.brd")
		(comment 1 "Tioga Pass / footprints 4411-4413 of 4770")
	)
	(layers
		(0 "F.Cu" signal "TOP")
		(4 "In1.Cu" signal "L2GND")
		(6 "In2.Cu" signal "L3")
		(8 "In3.Cu" signal "L4GND")
		(10 "In4.Cu" signal "L5")
		(12 "In5.Cu" signal "L6GND")
		(14 "In6.Cu" signal "L7VCC")
		(16 "In7.Cu" signal "L8VCC")
		(18 "In8.Cu" signal "L9GND")
		(20 "In9.Cu" signal "L10")
		(22 "In10.Cu" signal "L11GND")
		(24 "In11.Cu" signal "L12")
		(26 "In12.Cu" signal "L13GND")
		(2 "B.Cu" signal "BOTTOM")
		(9 "F.Adhes" user "F.Adhesive")
		(11 "B.Adhes" user "B.Adhesive")
		(13 "F.Paste" user "Package Geometry/Pastemask Top")
		(15 "B.Paste" user "Package Geometry/Pastemask Bottom")
		(5 "F.SilkS" user "Ref Des/Silkscreen Top")
		(7 "B.SilkS" user "Ref Des/Silkscreen Bottom")
		(1 "F.Mask" user "Board Geometry/Soldermask Top")
		(3 "B.Mask" user "Board Geometry/Soldermask Bottom")
		(17 "Dwgs.User" user "User.Drawings")
		(19 "Cmts.User" user "User.Comments")
		(21 "Eco1.User" user "User.Eco1")
		(23 "Eco2.User" user "User.Eco2")
		(25 "Edge.Cuts" user "Board Geometry/Outline")
		(27 "Margin" user)
		(31 "F.CrtYd" user "Package Geometry/Place Bound Top")
		(29 "B.CrtYd" user "Package Geometry/Place Bound Bottom")
		(35 "F.Fab" user "Ref Des/Assembly Top")
		(33 "B.Fab" user "Ref Des/Assembly Bottom")
	)
	(footprint ""
		(layer "B.Cu")
		(at 330.4794 -11.7094)
		(property "Reference" "R4U2"
			(at 0 0 0)
			(layer "B.SilkS")
			(hide yes)
			(effects
				(font
					(size 1.27 1.27)
				)
				(justify mirror)
			)
		)
		(property "Value" ""
			(at 0 0 0)
			(layer "B.Fab")
			(effects
				(font
					(size 1.27 1.27)
				)
				(justify mirror)
			)
		)
		(duplicate_pad_numbers_are_jumpers no)
		(fp_poly
			(pts
				(xy 0.2794 -0.1016) (xy -0.2794 -0.1016) (xy -0.2794 0.9906) (xy 0.2794 0.9906)
			)
			(stroke
				(width 0)
				(type default)
			)
			(fill no)
			(layer "B.CrtYd")
		)
		(fp_line
			(start -0.2794 -0.1016)
			(end 0.2794 -0.1016)
			(stroke
				(width 0.1)
				(type default)
			)
			(layer "B.Fab")
		)
		(fp_line
			(start -0.2794 0.9906)
			(end -0.2794 -0.1016)
			(stroke
				(width 0.1)
				(type default)
			)
			(layer "B.Fab")
		)
		(fp_line
			(start 0.2794 -0.1016)
			(end 0.2794 0.9906)
			(stroke
				(width 0.1)
				(type default)
			)
			(layer "B.Fab")
		)
		(fp_line
			(start 0.2794 0.9906)
			(end -0.2794 0.9906)
			(stroke
				(width 0.1)
				(type default)
			)
			(layer "B.Fab")
		)
		(pad "1" smd rect
			(at 0 0 180)
			(size 0.508 0.508)
			(layers "B.Cu" "B.Mask" "B.Paste")
			(net "PVPP_ABC")
		)
		(pad "2" smd rect
			(at 0 0.889 180)
			(size 0.508 0.508)
			(layers "B.Cu" "B.Mask" "B.Paste")
			(net "FM_DIMM_EVENT_COD_N")
		)
		(zone
			(layer "B.Cu")
			(hatch none 0.5)
			(connect_pads
				(clearance 0)
			)
			(min_thickness 0.25)
			(keepout
				(tracks allowed)
				(vias not_allowed)
				(pads allowed)
				(copperpour not_allowed)
				(footprints allowed)
			)
			(placement
				(enabled no)
				(sheetname "")
			)
			(fill
				(thermal_gap 0.5)
				(thermal_bridge_width 0.5)
				(island_removal_mode 0)
			)
			(polygon
				(pts
					(xy 330.7334 -11.4554) (xy 330.2254 -11.4554) (xy 330.2254 -11.0744) (xy 330.7334 -11.0744)
				)
			)
		)
		(zone
			(layer "B.Cu")
			(hatch none 0.5)
			(connect_pads
				(clearance 0)
			)
			(min_thickness 0.25)
			(keepout
				(tracks not_allowed)
				(vias allowed)
				(pads allowed)
				(copperpour not_allowed)
				(footprints allowed)
			)
			(placement
				(enabled no)
				(sheetname "")
			)
			(fill
				(thermal_gap 0.5)
				(thermal_bridge_width 0.5)
				(island_removal_mode 0)
			)
			(polygon
				(pts
					(xy 330.7334 -11.0744) (xy 330.2254 -11.0744) (xy 330.2254 -11.4554) (xy 330.7334 -11.4554)
				)
			)
		)
	)
	(footprint ""
		(layer "B.Cu")
		(at 347.79204 -149.168104 -90)
		(property "Reference" "C7A26"
			(at 0 0 90)
			(layer "B.SilkS")
			(hide yes)
			(effects
				(font
					(size 1.27 1.27)
				)
				(justify mirror)
			)
		)
		(property "Value" "*"
			(at -1.1811 -2.8194 270)
			(unlocked yes)
			(layer "B.Fab")
			(hide yes)
			(effects
				(font
					(size 1.27 1.016)
					(thickness 0.1524)
				)
				(justify mirror)
			)
		)
		(property "Device Type" "SC1U10V2KX-4-GP_SMD-BCG6-SC1U1A"
			(at -1.1811 -4.3434 270)
			(unlocked yes)
			(layer "B.Fab")
			(hide yes)
			(effects
				(font
					(size 1.27 1.016)
					(thickness 0.1524)
				)
				(justify mirror)
			)
		)
		(duplicate_pad_numbers_are_jumpers no)
		(fp_rect
			(start 0.4318 0.9525)
			(end -0.4318 -0.9525)
			(stroke
				(width 0)
				(type default)
			)
			(fill no)
			(layer "B.CrtYd")
		)
		(fp_rect
			(start 0.4318 0.9525)
			(end -0.4318 -0.9525)
			(stroke
				(width 0)
				(type default)
			)
			(fill no)
			(layer "B.Fab")
		)
		(pad "1" smd custom
			(at 0 -0.4445 90)
			(size 0.1524 0.1524)
			(layers "B.Cu" "B.Mask" "B.Paste")
			(net "P5V_STBY")
			(options
				(clearance outline)
				(anchor circle)
			)
			(primitives
				(gr_poly
					(pts
						(arc
							(start 0.3048 0.2032)
							(mid 0.275042 0.275042)
							(end 0.2032 0.3048)
						)
						(arc
							(start -0.2032 0.3048)
							(mid -0.275042 0.275042)
							(end -0.3048 0.2032)
						)
						(arc
							(start -0.3048 -0.2032)
							(mid -0.275042 -0.275042)
							(end -0.2032 -0.3048)
						)
						(arc
							(start 0.2032 -0.3048)
							(mid 0.275042 -0.275042)
							(end 0.3048 -0.2032)
						)
					)
					(width 0)
					(fill yes)
				)
			)
		)
		(pad "2" smd custom
			(at 0 0.4445 90)
			(size 0.1524 0.1524)
			(layers "B.Cu" "B.Mask" "B.Paste")
			(net "GND")
			(options
				(clearance outline)
				(anchor circle)
			)
			(primitives
				(gr_poly
					(pts
						(arc
							(start 0.3048 0.2032)
							(mid 0.275042 0.275042)
							(end 0.2032 0.3048)
						)
						(arc
							(start -0.2032 0.3048)
							(mid -0.275042 0.275042)
							(end -0.3048 0.2032)
						)
						(arc
							(start -0.3048 -0.2032)
							(mid -0.275042 -0.275042)
							(end -0.2032 -0.3048)
						)
						(arc
							(start 0.2032 -0.3048)
							(mid 0.275042 -0.275042)
							(end 0.3048 -0.2032)
						)
					)
					(width 0)
					(fill yes)
				)
			)
		)
	)
	(footprint ""
		(layer "B.Cu")
		(at 468.63 -46.6725 180)
		(property "Reference" "R9E12"
			(at 0 0 0)
			(layer "B.SilkS")
			(hide yes)
			(effects
				(font
					(size 1.27 1.27)
				)
				(justify mirror)
			)
		)
		(property "Value" ""
			(at 0 0 0)
			(layer "B.Fab")
			(effects
				(font
					(size 1.27 1.27)
				)
				(justify mirror)
			)
		)
		(duplicate_pad_numbers_are_jumpers no)
		(fp_poly
			(pts
				(xy 0.2794 -0.1016) (xy -0.2794 -0.1016) (xy -0.2794 0.9906) (xy 0.2794 0.9906)
			)
			(stroke
				(width 0)
				(type default)
			)
			(fill no)
			(layer "B.CrtYd")
		)
		(fp_line
			(start 0.2794 0.9906)
			(end -0.2794 0.9906)
			(stroke
				(width 0.1)
				(type default)
			)
			(layer "B.Fab")
		)
		(fp_line
			(start 0.2794 -0.1016)
			(end 0.2794 0.9906)
			(stroke
				(width 0.1)
				(type default)
			)
			(layer "B.Fab")
		)
		(fp_line
			(start -0.2794 0.9906)
			(end -0.2794 -0.1016)
			(stroke
				(width 0.1)
				(type default)
			)
			(layer "B.Fab")
		)
		(fp_line
			(start -0.2794 -0.1016)
			(end 0.2794 -0.1016)
			(stroke
				(width 0.1)
				(type default)
			)
			(layer "B.Fab")
		)
		(pad "1" smd rect
			(at 0 0)
			(size 0.508 0.508)
			(layers "B.Cu" "B.Mask" "B.Paste")
			(net "RST_PCIE_CPU_DEV3_R_N")
		)
		(pad "2" smd rect
			(at 0 0.889)
			(size 0.508 0.508)
			(layers "B.Cu" "B.Mask" "B.Paste")
			(net "RST_PCIE_CPU_DEV3_N")
		)
		(zone
			(layer "B.Cu")
			(hatch none 0.5)
			(connect_pads
				(clearance 0)
			)
			(min_thickness 0.25)
			(keepout
				(tracks not_allowed)
				(vias allowed)
				(pads allowed)
				(copperpour not_allowed)
				(footprints allowed)
			)
			(placement
				(enabled no)
				(sheetname "")
			)
			(fill
				(thermal_gap 0.5)
				(thermal_bridge_width 0.5)
				(island_removal_mode 0)
			)
			(polygon
				(pts
					(xy 468.376 -47.3075) (xy 468.884 -47.3075) (xy 468.884 -46.9265) (xy 468.376 -46.9265)
				)
			)
		)
		(zone
			(layer "B.Cu")
			(hatch none 0.5)
			(connect_pads
				(clearance 0)
			)
			(min_thickness 0.25)
			(keepout
				(tracks allowed)
				(vias not_allowed)
				(pads allowed)
				(copperpour not_allowed)
				(footprints allowed)
			)
			(placement
				(enabled no)
				(sheetname "")
			)
			(fill
				(thermal_gap 0.5)
				(thermal_bridge_width 0.5)
				(island_removal_mode 0)
			)
			(polygon
				(pts
					(xy 468.376 -46.9265) (xy 468.884 -46.9265) (xy 468.884 -47.3075) (xy 468.376 -47.3075)
				)
			)
		)
	)
)
